# BASEBOARD_FAB2 (Tioga Pass) — schematic netlist excerpt (pin names and nets, part order shuffled) for the footprints in the layout excerpt that follows; sources: Cadence DE-HDL packaged netlist, KiCad conversion of Wiwynn_Tioga_Pass_MB.brd

R7E14  RES  75K 1% CHIP  pkg 0402  page 241 : A = VR_P5V_STBY_RT ; B = AGND_P5V_STBY
C3D15  CAP_A  22.0UF 4V 20% X6S  pkg 0603V  page 76 : A = PVCCIO_CPU1 ; B = GND
R25W83  RES  0.0 5% CHIP  pkg 0402  page 146 : A = FM_BMC_NMI_N ; B = FM_BMC_NMI_N_R

(kicad_pcb
	(version 20260206)
	(generator "pcbnew")
	(generator_version "10.0")
	(general
		(thickness 1.6)
		(legacy_teardrops no)
	)
	(paper "A4")
	(title_block
		(title "Wiwynn_Tioga_Pass_MB.brd")
		(comment 1 "Tioga Pass / footprints 1819-1821 of 4770")
	)
	(layers
		(0 "F.Cu" signal "TOP")
		(4 "In1.Cu" signal "L2GND")
		(6 "In2.Cu" signal "L3")
		(8 "In3.Cu" signal "L4GND")
		(10 "In4.Cu" signal "L5")
		(12 "In5.Cu" signal "L6GND")
		(14 "In6.Cu" signal "L7VCC")
		(16 "In7.Cu" signal "L8VCC")
		(18 "In8.Cu" signal "L9GND")
		(20 "In9.Cu" signal "L10")
		(22 "In10.Cu" signal "L11GND")
		(24 "In11.Cu" signal "L12")
		(26 "In12.Cu" signal "L13GND")
		(2 "B.Cu" signal "BOTTOM")
		(9 "F.Adhes" user "F.Adhesive")
		(11 "B.Adhes" user "B.Adhesive")
		(13 "F.Paste" user "Package Geometry/Pastemask Top")
		(15 "B.Paste" user "Package Geometry/Pastemask Bottom")
		(5 "F.SilkS" user "Ref Des/Silkscreen Top")
		(7 "B.SilkS" user "Ref Des/Silkscreen Bottom")
		(1 "F.Mask" user "Board Geometry/Soldermask Top")
		(3 "B.Mask" user "Board Geometry/Soldermask Bottom")
		(17 "Dwgs.User" user "User.Drawings")
		(19 "Cmts.User" user "User.Comments")
		(21 "Eco1.User" user "User.Eco1")
		(23 "Eco2.User" user "User.Eco2")
		(25 "Edge.Cuts" user "Board Geometry/Outline")
		(27 "Margin" user)
		(31 "F.CrtYd" user "Package Geometry/Place Bound Top")
		(29 "B.CrtYd" user "Package Geometry/Place Bound Bottom")
		(35 "F.Fab" user "Ref Des/Assembly Top")
		(33 "B.Fab" user "Ref Des/Assembly Bottom")
	)
	(footprint ""
		(layer "F.Cu")
		(at 390.525 -71.0565 180)
		(property "Reference" "R7E14"
			(at 0 0 180)
			(layer "F.SilkS")
			(hide yes)
			(effects
				(font
					(size 1.27 1.27)
				)
			)
		)
		(property "Value" ""
			(at 0 0 180)
			(layer "F.Fab")
			(effects
				(font
					(size 1.27 1.27)
				)
			)
		)
		(duplicate_pad_numbers_are_jumpers no)
		(fp_poly
			(pts
				(xy -0.2794 -0.1016) (xy 0.2794 -0.1016) (xy 0.2794 0.9906) (xy -0.2794 0.9906)
			)
			(stroke
				(width 0)
				(type default)
			)
			(fill no)
			(layer "F.CrtYd")
		)
		(fp_line
			(start 0.2794 0.9906)
			(end 0.2794 -0.1016)
			(stroke
				(width 0.1)
				(type default)
			)
			(layer "F.Fab")
		)
		(fp_line
			(start 0.2794 -0.1016)
			(end -0.2794 -0.1016)
			(stroke
				(width 0.1)
				(type default)
			)
			(layer "F.Fab")
		)
		(fp_line
			(start -0.2794 0.9906)
			(end 0.2794 0.9906)
			(stroke
				(width 0.1)
				(type default)
			)
			(layer "F.Fab")
		)
		(fp_line
			(start -0.2794 -0.1016)
			(end -0.2794 0.9906)
			(stroke
				(width 0.1)
				(type default)
			)
			(layer "F.Fab")
		)
		(pad "1" smd rect
			(at 0 0 180)
			(size 0.508 0.508)
			(layers "F.Cu" "F.Mask" "F.Paste")
			(net "VR_P5V_STBY_RT")
		)
		(pad "2" smd rect
			(at 0 0.889 180)
			(size 0.508 0.508)
			(layers "F.Cu" "F.Mask" "F.Paste")
			(net "AGND_P5V_STBY")
		)
		(zone
			(layer "F.Cu")
			(hatch none 0.5)
			(connect_pads
				(clearance 0)
			)
			(min_thickness 0.25)
			(keepout
				(tracks not_allowed)
				(vias allowed)
				(pads allowed)
				(copperpour not_allowed)
				(footprints allowed)
			)
			(placement
				(enabled no)
				(sheetname "")
			)
			(fill
				(thermal_gap 0.5)
				(thermal_bridge_width 0.5)
				(island_removal_mode 0)
			)
			(polygon
				(pts
					(xy 390.779 -71.6915) (xy 390.271 -71.6915) (xy 390.271 -71.3105) (xy 390.779 -71.3105)
				)
			)
		)
		(zone
			(layer "F.Cu")
			(hatch none 0.5)
			(connect_pads
				(clearance 0)
			)
			(min_thickness 0.25)
			(keepout
				(tracks allowed)
				(vias not_allowed)
				(pads allowed)
				(copperpour not_allowed)
				(footprints allowed)
			)
			(placement
				(enabled no)
				(sheetname "")
			)
			(fill
				(thermal_gap 0.5)
				(thermal_bridge_width 0.5)
				(island_removal_mode 0)
			)
			(polygon
				(pts
					(xy 390.779 -71.3105) (xy 390.271 -71.3105) (xy 390.271 -71.6915) (xy 390.779 -71.6915)
				)
			)
		)
	)
	(footprint ""
		(layer "F.Cu")
		(at 426.681646 -48.968152)
		(property "Reference" "R25W83"
			(at -0.8382 -0.67818 0)
			(unlocked yes)
			(layer "F.SilkS")
			(effects
				(font
					(size 0.4064 0.254)
					(thickness 0.1524)
				)
				(justify left)
			)
		)
		(property "Value" ""
			(at 0 0 0)
			(layer "F.Fab")
			(effects
				(font
					(size 1.27 1.27)
				)
			)
		)
		(duplicate_pad_numbers_are_jumpers no)
		(fp_poly
			(pts
				(xy -0.2794 -0.1016) (xy 0.2794 -0.1016) (xy 0.2794 0.9906) (xy -0.2794 0.9906)
			)
			(stroke
				(width 0)
				(type default)
			)
			(fill no)
			(layer "F.CrtYd")
		)
		(fp_line
			(start -0.2794 -0.1016)
			(end -0.2794 0.9906)
			(stroke
				(width 0.1)
				(type default)
			)
			(layer "F.Fab")
		)
		(fp_line
			(start -0.2794 0.9906)
			(end 0.2794 0.9906)
			(stroke
				(width 0.1)
				(type default)
			)
			(layer "F.Fab")
		)
		(fp_line
			(start 0.2794 -0.1016)
			(end -0.2794 -0.1016)
			(stroke
				(width 0.1)
				(type default)
			)
			(layer "F.Fab")
		)
		(fp_line
			(start 0.2794 0.9906)
			(end 0.2794 -0.1016)
			(stroke
				(width 0.1)
				(type default)
			)
			(layer "F.Fab")
		)
		(pad "1" smd rect
			(at 0 0)
			(size 0.508 0.508)
			(layers "F.Cu" "F.Mask" "F.Paste")
			(net "FM_BMC_NMI_N")
		)
		(pad "2" smd rect
			(at 0 0.889)
			(size 0.508 0.508)
			(layers "F.Cu" "F.Mask" "F.Paste")
			(net "FM_BMC_NMI_N_R")
		)
		(zone
			(layer "F.Cu")
			(hatch none 0.5)
			(connect_pads
				(clearance 0)
			)
			(min_thickness 0.25)
			(keepout
				(tracks allowed)
				(vias not_allowed)
				(pads allowed)
				(copperpour not_allowed)
				(footprints allowed)
			)
			(placement
				(enabled no)
				(sheetname "")
			)
			(fill
				(thermal_gap 0.5)
				(thermal_bridge_width 0.5)
				(island_removal_mode 0)
			)
			(polygon
				(pts
					(xy 426.427646 -48.714152) (xy 426.935646 -48.714152) (xy 426.935646 -48.333152) (xy 426.427646 -48.333152)
				)
			)
		)
		(zone
			(layer "F.Cu")
			(hatch none 0.5)
			(connect_pads
				(clearance 0)
			)
			(min_thickness 0.25)
			(keepout
				(tracks not_allowed)
				(vias allowed)
				(pads allowed)
				(copperpour not_allowed)
				(footprints allowed)
			)
			(placement
				(enabled no)
				(sheetname "")
			)
			(fill
				(thermal_gap 0.5)
				(thermal_bridge_width 0.5)
				(island_removal_mode 0)
			)
			(polygon
				(pts
					(xy 426.427646 -48.333152) (xy 426.935646 -48.333152) (xy 426.935646 -48.714152) (xy 426.427646 -48.714152)
				)
			)
		)
	)
	(footprint ""
		(layer "F.Cu")
		(at 113.427002 -77.382116)
		(property "Reference" "C3D15"
			(at 0 0 0)
			(layer "F.SilkS")
			(hide yes)
			(effects
				(font
					(size 1.27 1.27)
				)
			)
		)
		(property "Value" ""
			(at 0 0 0)
			(layer "F.Fab")
			(effects
				(font
					(size 1.27 1.27)
				)
			)
		)
		(duplicate_pad_numbers_are_jumpers no)
		(fp_poly
			(pts
				(xy -0.4953 -0.2032) (xy 0.4953 -0.2032) (xy 0.4953 1.6002) (xy -0.4953 1.6002)
			)
			(stroke
				(width 0)
				(type default)
			)
			(fill no)
			(layer "F.CrtYd")
		)
		(fp_line
			(start -0.4953 -0.2032)
			(end 0.4953 -0.2032)
			(stroke
				(width 0.1)
				(type default)
			)
			(layer "F.Fab")
		)
		(fp_line
			(start -0.4953 1.6002)
			(end -0.4953 -0.2032)
			(stroke
				(width 0.1)
				(type default)
			)
			(layer "F.Fab")
		)
		(fp_line
			(start 0.4953 -0.2032)
			(end 0.4953 1.6002)
			(stroke
				(width 0.1)
				(type default)
			)
			(layer "F.Fab")
		)
		(fp_line
			(start 0.4953 1.6002)
			(end -0.4953 1.6002)
			(stroke
				(width 0.1)
				(type default)
			)
			(layer "F.Fab")
		)
		(pad "1" smd rect
			(at 0 0)
			(size 0.762 0.889)
			(layers "F.Cu" "F.Mask" "F.Paste")
			(net "PVCCIO_CPU1")
		)
		(pad "2" smd rect
			(at 0 1.397)
			(size 0.762 0.889)
			(layers "F.Cu" "F.Mask" "F.Paste")
			(net "GND")
		)
		(zone
			(layer "F.Cu")
			(hatch none 0.5)
			(connect_pads
				(clearance 0)
			)
			(min_thickness 0.25)
			(keepout
				(tracks not_allowed)
				(vias allowed)
				(pads allowed)
				(copperpour not_allowed)
				(footprints allowed)
			)
			(placement
				(enabled no)
				(sheetname "")
			)
			(fill
				(thermal_gap 0.5)
				(thermal_bridge_width 0.5)
				(island_removal_mode 0)
			)
			(polygon
				(pts
					(xy 113.046002 -76.937616) (xy 113.808002 -76.937616) (xy 113.808002 -76.429616) (xy 113.046002 -76.429616)
				)
			)
		)
	)
)
